(kicad_pcb
	(version 20241229)
	(generator "pcbnew")
	(generator_version "9.0")
	(general
		(thickness 1.294)
		(legacy_teardrops no)
	)
	(paper "A3")
	(title_block
		(title "Kintex 410T devboard")
		(date "2024-04-03")
		(rev "1.1.2")
		(comment 9 "footprints 39-41 of 975")
	)
	(layers
		(0 "F.Cu" mixed)
		(4 "In1.Cu" power)
		(6 "In2.Cu" power)
		(8 "In3.Cu" mixed)
		(10 "In4.Cu" power)
		(12 "In5.Cu" mixed)
		(14 "In6.Cu" power)
		(16 "In7.Cu" mixed)
		(18 "In8.Cu" power)
		(2 "B.Cu" mixed)
		(9 "F.Adhes" user "F.Adhesive")
		(11 "B.Adhes" user "B.Adhesive")
		(13 "F.Paste" user)
		(15 "B.Paste" user)
		(5 "F.SilkS" user "F.Silkscreen")
		(7 "B.SilkS" user "B.Silkscreen")
		(1 "F.Mask" user)
		(3 "B.Mask" user)
		(17 "Dwgs.User" user "User.Drawings")
		(19 "Cmts.User" user "User.Comments")
		(21 "Eco1.User" user "User.Eco1")
		(23 "Eco2.User" user "User.Eco2")
		(25 "Edge.Cuts" user)
		(27 "Margin" user)
		(31 "F.CrtYd" user "F.Courtyard")
		(29 "B.CrtYd" user "B.Courtyard")
		(35 "F.Fab" user)
		(33 "B.Fab" user)
	)
	(footprint "antmicro-footprints:LED_0603_1608Metric_G"
		(layer "F.Cu")
		(at 266.585 139.31 180)
		(descr "LED SMD 0603 Green")
		(tags "LED SMD 0603 Green")
		(property "Reference" "D26"
			(at -1.065 -1.59 0)
			(layer "F.SilkS")
			(effects
				(font
					(size 0.7 0.7)
					(thickness 0.15)
				)
				(justify right bottom)
			)
		)
		(property "Value" "LED_G_0603_KP-1608CGCK"
			(at -0.001 1.599 0)
			(layer "F.Fab")
			(effects
				(font
					(size 0.7 0.7)
					(thickness 0.15)
				)
				(justify right bottom)
			)
		)
		(property "Description" "LED, Green, SMD, 0603, 20 mA, 2.1 V, 570 nm"
			(at 0 0 180)
			(layer "F.Fab")
			(hide yes)
			(effects
				(font
					(size 1.27 1.27)
					(thickness 0.15)
				)
			)
		)
		(property "Author" "Antmicro"
			(at 533.17 278.62 0)
			(layer "F.Fab")
			(hide yes)
			(effects
				(font
					(size 1 1)
					(thickness 0.15)
				)
			)
		)
		(property "Color" "Green"
			(at 533.17 278.62 0)
			(layer "F.Fab")
			(hide yes)
			(effects
				(font
					(size 1 1)
					(thickness 0.15)
				)
			)
		)
		(property "License" "Apache-2.0"
			(at 533.17 278.62 0)
			(layer "F.Fab")
			(hide yes)
			(effects
				(font
					(size 1 1)
					(thickness 0.15)
				)
			)
		)
		(property "MPN" "KP-1608CGCK"
			(at 533.17 278.62 0)
			(layer "F.Fab")
			(hide yes)
			(effects
				(font
					(size 1 1)
					(thickness 0.15)
				)
			)
		)
		(property "Manufacturer" "Kingbright"
			(at 533.17 278.62 0)
			(layer "F.Fab")
			(hide yes)
			(effects
				(font
					(size 1 1)
					(thickness 0.15)
				)
			)
		)
		(sheetname "USB PHY")
		(sheetfile "usb-phy.kicad_sch")
		(attr smd)
		(fp_line
			(start 0.22 0.35)
			(end -0.22 0.35)
			(stroke
				(width 0.15)
				(type solid)
			)
			(layer "F.SilkS")
		)
		(fp_line
			(start 0.22 -0.35)
			(end -0.22 -0.35)
			(stroke
				(width 0.15)
				(type solid)
			)
			(layer "F.SilkS")
		)
		(fp_line
			(start 0.105328 0.201008)
			(end 0.105328 -0.198992)
			(stroke
				(width 0.1)
				(type solid)
			)
			(layer "F.SilkS")
		)
		(fp_line
			(start 0.105328 0.201008)
			(end -0.094672 0.001008)
			(stroke
				(width 0.1)
				(type solid)
			)
			(layer "F.SilkS")
		)
		(fp_line
			(start 0.105328 0.001008)
			(end 0.24 0.001)
			(stroke
				(width 0.1)
				(type solid)
			)
			(layer "F.SilkS")
		)
		(fp_line
			(start -0.094672 0.201008)
			(end -0.094672 -0.198992)
			(stroke
				(width 0.1)
				(type solid)
			)
			(layer "F.SilkS")
		)
		(fp_line
			(start -0.094672 0.001008)
			(end 0.105328 -0.198992)
			(stroke
				(width 0.1)
				(type solid)
			)
			(layer "F.SilkS")
		)
		(fp_line
			(start -0.094672 0.001008)
			(end -0.24 0.001008)
			(stroke
				(width 0.1)
				(type solid)
			)
			(layer "F.SilkS")
		)
		(fp_line
			(start -1.18 -0.319)
			(end -1.18 0.321)
			(stroke
				(width 0.15)
				(type solid)
			)
			(layer "F.SilkS")
		)
		(fp_rect
			(start 1.25 0.65)
			(end -1.25 -0.65)
			(stroke
				(width 0.05)
				(type solid)
			)
			(fill no)
			(layer "F.CrtYd")
		)
		(fp_line
			(start 0.599 0)
			(end 0.201 0)
			(stroke
				(width 0.15)
				(type solid)
			)
			(layer "F.Fab")
		)
		(fp_line
			(start 0.201 0.2)
			(end 0.201 0)
			(stroke
				(width 0.15)
				(type solid)
			)
			(layer "F.Fab")
		)
		(fp_line
			(start 0.201 0)
			(end 0.201 -0.202)
			(stroke
				(width 0.15)
				(type solid)
			)
			(layer "F.Fab")
		)
		(fp_line
			(start 0.201 -0.202)
			(end -0.101 0)
			(stroke
				(width 0.15)
				(type solid)
			)
			(layer "F.Fab")
		)
		(fp_line
			(start -0.101 0)
			(end 0.201 0.2)
			(stroke
				(width 0.15)
				(type solid)
			)
			(layer "F.Fab")
		)
		(fp_line
			(start -0.199 0.2)
			(end -0.199 0.1)
			(stroke
				(width 0.15)
				(type solid)
			)
			(layer "F.Fab")
		)
		(fp_line
			(start -0.199 0)
			(end -0.597 0)
			(stroke
				(width 0.15)
				(type solid)
			)
			(layer "F.Fab")
		)
		(fp_line
			(start -0.199 -0.202)
			(end -0.199 0.1)
			(stroke
				(width 0.15)
				(type solid)
			)
			(layer "F.Fab")
		)
		(fp_rect
			(start 0.848 0.4)
			(end -0.85 -0.402)
			(stroke
				(width 0.15)
				(type solid)
			)
			(fill no)
			(layer "F.Fab")
		)
		(pad "1" smd roundrect
			(at -0.7 0)
			(size 0.8 1)
			(layers "F.Cu" "F.Mask" "F.Paste")
			(roundrect_rratio 0.2)
			(net 1 "GND")
			(pinfunction "C")
			(pintype "passive")
		)
		(pad "2" smd roundrect
			(at 0.7 0)
			(size 0.8 1)
			(layers "F.Cu" "F.Mask" "F.Paste")
			(roundrect_rratio 0.2)
			(net 790 "Net-(D26-A)")
			(pinfunction "A")
			(pintype "passive")
		)
	)
	(footprint "antmicro-footprints:R_0402_1005Metric"
		(layer "F.Cu")
		(at 236.2 132.55 180)
		(descr "Resistor SMD 0402")
		(tags "resistor SMD 0402")
		(property "Reference" "R176"
			(at 1.825 3.525 180)
			(layer "F.SilkS")
			(effects
				(font
					(size 0.7 0.7)
					(thickness 0.15)
				)
				(justify left bottom)
			)
		)
		(property "Value" "R_33R_0402"
			(at 0 1.4 180)
			(layer "F.Fab")
			(effects
				(font
					(size 0.7 0.7)
					(thickness 0.15)
				)
				(justify left bottom)
			)
		)
		(property "Description" "SMD Chip Resistor, 33 ohm, ± 1%, 62.5 mW, 0402 [1005 Metric], Thick Film, General Purpose"
			(at 0 0 180)
			(layer "F.Fab")
			(hide yes)
			(effects
				(font
					(size 1.27 1.27)
					(thickness 0.15)
				)
			)
		)
		(property "Author" "Antmicro"
			(at 472.4 265.1 0)
			(layer "F.Fab")
			(hide yes)
			(effects
				(font
					(size 1 1)
					(thickness 0.15)
				)
			)
		)
		(property "License" "Apache-2.0"
			(at 472.4 265.1 0)
			(layer "F.Fab")
			(hide yes)
			(effects
				(font
					(size 1 1)
					(thickness 0.15)
				)
			)
		)
		(property "MPN" "CR0402-FX-33R0GLF"
			(at 472.4 265.1 0)
			(layer "F.Fab")
			(hide yes)
			(effects
				(font
					(size 1 1)
					(thickness 0.15)
				)
			)
		)
		(property "Manufacturer" "Bourns"
			(at 472.4 265.1 0)
			(layer "F.Fab")
			(hide yes)
			(effects
				(font
					(size 1 1)
					(thickness 0.15)
				)
			)
		)
		(property "Tolerance" "1%"
			(at 472.4 265.1 0)
			(layer "F.Fab")
			(hide yes)
			(effects
				(font
					(size 1 1)
					(thickness 0.15)
				)
			)
		)
		(property "Val" "33R"
			(at 472.4 265.1 0)
			(layer "F.Fab")
			(hide yes)
			(effects
				(font
					(size 1 1)
					(thickness 0.15)
				)
			)
		)
		(sheetname "USB PHY")
		(sheetfile "usb-phy.kicad_sch")
		(attr smd)
		(fp_rect
			(start -0.925 -0.47)
			(end 0.925 0.47)
			(stroke
				(width 0.05)
				(type default)
			)
			(fill no)
			(layer "F.CrtYd")
		)
		(fp_rect
			(start -0.5 -0.25)
			(end 0.5 0.25)
			(stroke
				(width 0.15)
				(type solid)
			)
			(fill no)
			(layer "F.Fab")
		)
		(pad "1" smd roundrect
			(at -0.48 0 180)
			(size 0.59 0.64)
			(layers "F.Cu" "F.Mask" "F.Paste")
			(roundrect_rratio 0.25)
			(net 368 "Net-(U22-B1Y)")
			(pintype "passive")
		)
		(pad "2" smd roundrect
			(at 0.48 0 180)
			(size 0.59 0.64)
			(layers "F.Cu" "F.Mask" "F.Paste")
			(roundrect_rratio 0.25)
			(net 165 "/FPGA Config/JTAG.TCK")
			(pintype "passive")
		)
	)
	(footprint "antmicro-footprints:C_0402_1005Metric"
		(layer "F.Cu")
		(at 173.570001 121.430001 180)
		(descr "Capacitor SMD 0402")
		(tags "capacitor SMD 0402")
		(property "Reference" "C312"
			(at -3.729999 -0.369999 0)
			(layer "F.SilkS")
			(effects
				(font
					(size 0.7 0.7)
					(thickness 0.15)
				)
				(justify right bottom)
			)
		)
		(property "Value" "C_100n_0402"
			(at 0 1.4 0)
			(layer "F.Fab")
			(effects
				(font
					(size 0.7 0.7)
					(thickness 0.15)
				)
				(justify right bottom)
			)
		)
		(property "Description" "SMD Multilayer Ceramic Capacitor, 0.1 µF, 50 V, 0402 [1005 Metric], ± 10%, X5R, GRM Series"
			(at 0 0 180)
			(layer "F.Fab")
			(hide yes)
			(effects
				(font
					(size 1.27 1.27)
					(thickness 0.15)
				)
			)
		)
		(property "Author" "Antmicro"
			(at 347.140002 242.860002 0)
			(layer "F.Fab")
			(hide yes)
			(effects
				(font
					(size 1 1)
					(thickness 0.15)
				)
			)
		)
		(property "Dielectric" "X5R"
			(at 347.140002 242.860002 0)
			(layer "F.Fab")
			(hide yes)
			(effects
				(font
					(size 1 1)
					(thickness 0.15)
				)
			)
		)
		(property "License" "Apache-2.0"
			(at 347.140002 242.860002 0)
			(layer "F.Fab")
			(hide yes)
			(effects
				(font
					(size 1 1)
					(thickness 0.15)
				)
			)
		)
		(property "MPN" "GRM155R61H104KE14D"
			(at 347.140002 242.860002 0)
			(layer "F.Fab")
			(hide yes)
			(effects
				(font
					(size 1 1)
					(thickness 0.15)
				)
			)
		)
		(property "Manufacturer" "Murata"
			(at 347.140002 242.860002 0)
			(layer "F.Fab")
			(hide yes)
			(effects
				(font
					(size 1 1)
					(thickness 0.15)
				)
			)
		)
		(property "Val" "100n"
			(at 347.140002 242.860002 0)
			(layer "F.Fab")
			(hide yes)
			(effects
				(font
					(size 1 1)
					(thickness 0.15)
				)
			)
		)
		(property "Voltage" "50V"
			(at 347.140002 242.860002 0)
			(layer "F.Fab")
			(hide yes)
			(effects
				(font
					(size 1 1)
					(thickness 0.15)
				)
			)
		)
		(sheetname "FMC+ HSPC")
		(sheetfile "fmc-hspc.kicad_sch")
		(attr smd)
		(fp_rect
			(start -0.925 -0.47)
			(end 0.925 0.47)
			(stroke
				(width 0.05)
				(type default)
			)
			(fill no)
			(layer "F.CrtYd")
		)
		(fp_line
			(start 0.504 0.248)
			(end -0.494 0.248)
			(stroke
				(width 0.15)
				(type solid)
			)
			(layer "F.Fab")
		)
		(fp_line
			(start 0.504 -0.25)
			(end 0.504 0.248)
			(stroke
				(width 0.15)
				(type solid)
			)
			(layer "F.Fab")
		)
		(fp_line
			(start -0.494 0.248)
			(end -0.494 -0.25)
			(stroke
				(width 0.15)
				(type solid)
			)
			(layer "F.Fab")
		)
		(fp_line
			(start -0.494 -0.25)
			(end 0.504 -0.25)
			(stroke
				(width 0.15)
				(type solid)
			)
			(layer "F.Fab")
		)
		(pad "1" smd roundrect
			(at -0.48 0 180)
			(size 0.59 0.64)
			(layers "F.Cu" "F.Mask" "F.Paste")
			(roundrect_rratio 0.25)
			(net 122 "/FMC+ HSPC/GTX115.TX0_P")
			(pintype "passive")
		)
		(pad "2" smd roundrect
			(at 0.48 0 180)
			(size 0.59 0.64)
			(layers "F.Cu" "F.Mask" "F.Paste")
			(roundrect_rratio 0.25)
			(net 119 "/FMC+ HSPC/GTX_TX7_C_P")
			(pintype "passive")
		)
	)
)
